# T6G (Grand Teton) — schematic netlist excerpt (pin names and nets, part order shuffled) for the footprints in the layout excerpt that follows; sources: Cadence DE-HDL packaged netlist, KiCad conversion of 04192023_DAF0TMB3IC0_F0TG_MB_C_brd_V02_OCP.brd

C8022  Q_CAP  100NF 50V 10% X7R  pkg C0402  page 268 : A = P12V_AUX ; B = GND
PR5484  Q_RES  30.1K 1% CHIP  pkg 0402LF  page 134 : A = P12V_OCP_CB_1 ; B = GND

(kicad_pcb
	(version 20260206)
	(generator "pcbnew")
	(generator_version "10.0")
	(general
		(thickness 1.6)
		(legacy_teardrops no)
	)
	(paper "A4")
	(title_block
		(title "04192023_DAF0TMB3IC0_F0TG_MB_C_brd_V02_OCP.brd")
		(comment 1 "Grand Teton / footprints 1978-1979 of 8354")
	)
	(layers
		(0 "F.Cu" signal "TOP")
		(4 "In1.Cu" signal "GND")
		(6 "In2.Cu" signal "IN1")
		(8 "In3.Cu" signal "GND1")
		(10 "In4.Cu" signal "IN2")
		(12 "In5.Cu" signal "GND2")
		(14 "In6.Cu" signal "IN3")
		(16 "In7.Cu" signal "GND3")
		(18 "In8.Cu" signal "VCC")
		(20 "In9.Cu" signal "VCC1")
		(22 "In10.Cu" signal "GND4")
		(24 "In11.Cu" signal "IN4")
		(26 "In12.Cu" signal "GND5")
		(28 "In13.Cu" signal "IN5")
		(30 "In14.Cu" signal "GND6")
		(32 "In15.Cu" signal "IN6")
		(34 "In16.Cu" signal "GND7")
		(2 "B.Cu" signal "BOTTOM")
		(9 "F.Adhes" user "F.Adhesive")
		(11 "B.Adhes" user "B.Adhesive")
		(13 "F.Paste" user "Package Geometry/Pastemask Top")
		(15 "B.Paste" user "Package Geometry/Pastemask Bottom")
		(5 "F.SilkS" user "Ref Des/Silkscreen Top")
		(7 "B.SilkS" user "Ref Des/Silkscreen Bottom")
		(1 "F.Mask" user "Board Geometry/Soldermask Top")
		(3 "B.Mask" user "Board Geometry/Soldermask Bottom")
		(17 "Dwgs.User" user "User.Drawings")
		(19 "Cmts.User" user "User.Comments")
		(21 "Eco1.User" user "User.Eco1")
		(23 "Eco2.User" user "User.Eco2")
		(25 "Edge.Cuts" user "Board Geometry/Outline")
		(27 "Margin" user)
		(31 "F.CrtYd" user "Package Geometry/Place Bound Top")
		(29 "B.CrtYd" user "Package Geometry/Place Bound Bottom")
		(35 "F.Fab" user "Ref Des/Assembly Top")
		(33 "B.Fab" user "Ref Des/Assembly Bottom")
	)
	(footprint ""
		(layer "F.Cu")
		(at 447.687192 -21.236178 180)
		(property "Reference" "PR5484"
			(at 0 0 180)
			(layer "F.SilkS")
			(hide yes)
			(effects
				(font
					(size 1.27 1.27)
				)
			)
		)
		(property "Value" ""
			(at 0 0 180)
			(layer "F.Fab")
			(effects
				(font
					(size 1.27 1.27)
				)
			)
		)
		(duplicate_pad_numbers_are_jumpers no)
		(fp_line
			(start 0.7874 0.4064)
			(end -0.7874 0.4064)
			(stroke
				(width 0.1524)
				(type default)
			)
			(layer "F.SilkS")
		)
		(fp_line
			(start 0.7874 -0.4064)
			(end 0.7874 0.4064)
			(stroke
				(width 0.1524)
				(type default)
			)
			(layer "F.SilkS")
		)
		(fp_line
			(start -0.7874 0.4064)
			(end -0.7874 -0.4064)
			(stroke
				(width 0.1524)
				(type default)
			)
			(layer "F.SilkS")
		)
		(fp_line
			(start -0.7874 -0.4064)
			(end 0.7874 -0.4064)
			(stroke
				(width 0.1524)
				(type default)
			)
			(layer "F.SilkS")
		)
		(fp_line
			(start 0.67945 0.3048)
			(end 0.120396 0.3048)
			(stroke
				(width 0.1)
				(type default)
			)
			(layer "F.Fab")
		)
		(fp_line
			(start 0.67945 -0.3048)
			(end 0.67945 0.3048)
			(stroke
				(width 0.1)
				(type default)
			)
			(layer "F.Fab")
		)
		(fp_line
			(start 0.12065 -0.2794)
			(end 0.12065 -0.3048)
			(stroke
				(width 0.1)
				(type default)
			)
			(layer "F.Fab")
		)
		(fp_line
			(start 0.12065 -0.3048)
			(end 0.67945 -0.3048)
			(stroke
				(width 0.1)
				(type default)
			)
			(layer "F.Fab")
		)
		(fp_line
			(start 0.120396 0.3048)
			(end 0.120396 0.2794)
			(stroke
				(width 0.1)
				(type default)
			)
			(layer "F.Fab")
		)
		(fp_line
			(start 0.120396 0.2794)
			(end -0.12065 0.2794)
			(stroke
				(width 0.1)
				(type default)
			)
			(layer "F.Fab")
		)
		(fp_line
			(start -0.12065 0.3048)
			(end -0.67945 0.3048)
			(stroke
				(width 0.1)
				(type default)
			)
			(layer "F.Fab")
		)
		(fp_line
			(start -0.12065 0.2794)
			(end -0.12065 0.3048)
			(stroke
				(width 0.1)
				(type default)
			)
			(layer "F.Fab")
		)
		(fp_line
			(start -0.12065 -0.2794)
			(end 0.12065 -0.2794)
			(stroke
				(width 0.1)
				(type default)
			)
			(layer "F.Fab")
		)
		(fp_line
			(start -0.12065 -0.305054)
			(end -0.12065 -0.2794)
			(stroke
				(width 0.1)
				(type default)
			)
			(layer "F.Fab")
		)
		(fp_line
			(start -0.67945 0.3048)
			(end -0.67945 -0.305054)
			(stroke
				(width 0.1)
				(type default)
			)
			(layer "F.Fab")
		)
		(fp_line
			(start -0.67945 -0.305054)
			(end -0.12065 -0.305054)
			(stroke
				(width 0.1)
				(type default)
			)
			(layer "F.Fab")
		)
		(pad "1" smd circle
			(at -0.40005 0 180)
			(size 0 0)
			(layers "F.Cu" "F.Mask" "F.Paste")
			(net "P12V_OCP_CB_1")
		)
		(pad "2" smd circle
			(at 0.40005 0 180)
			(size 0 0)
			(layers "F.Cu" "F.Mask" "F.Paste")
			(net "GND")
		)
	)
	(footprint ""
		(layer "F.Cu")
		(at 139.065 -116.586 180)
		(property "Reference" "C8022"
			(at 0 0 180)
			(layer "F.SilkS")
			(hide yes)
			(effects
				(font
					(size 1.27 1.27)
				)
			)
		)
		(property "Value" ""
			(at 0 0 180)
			(layer "F.Fab")
			(effects
				(font
					(size 1.27 1.27)
				)
			)
		)
		(duplicate_pad_numbers_are_jumpers no)
		(fp_line
			(start 0.7874 0.4064)
			(end -0.7874 0.4064)
			(stroke
				(width 0.1524)
				(type default)
			)
			(layer "F.SilkS")
		)
		(fp_line
			(start 0.7874 -0.4064)
			(end 0.7874 0.4064)
			(stroke
				(width 0.1524)
				(type default)
			)
			(layer "F.SilkS")
		)
		(fp_line
			(start -0.7874 0.4064)
			(end -0.7874 -0.4064)
			(stroke
				(width 0.1524)
				(type default)
			)
			(layer "F.SilkS")
		)
		(fp_line
			(start -0.7874 -0.4064)
			(end 0.7874 -0.4064)
			(stroke
				(width 0.1524)
				(type default)
			)
			(layer "F.SilkS")
		)
		(fp_line
			(start 0.67945 0.3048)
			(end 0.120396 0.3048)
			(stroke
				(width 0.1)
				(type default)
			)
			(layer "F.Fab")
		)
		(fp_line
			(start 0.67945 -0.3048)
			(end 0.67945 0.3048)
			(stroke
				(width 0.1)
				(type default)
			)
			(layer "F.Fab")
		)
		(fp_line
			(start 0.12065 -0.2794)
			(end 0.12065 -0.3048)
			(stroke
				(width 0.1)
				(type default)
			)
			(layer "F.Fab")
		)
		(fp_line
			(start 0.12065 -0.3048)
			(end 0.67945 -0.3048)
			(stroke
				(width 0.1)
				(type default)
			)
			(layer "F.Fab")
		)
		(fp_line
			(start 0.120396 0.3048)
			(end 0.120396 0.2794)
			(stroke
				(width 0.1)
				(type default)
			)
			(layer "F.Fab")
		)
		(fp_line
			(start 0.120396 0.2794)
			(end -0.12065 0.2794)
			(stroke
				(width 0.1)
				(type default)
			)
			(layer "F.Fab")
		)
		(fp_line
			(start -0.12065 0.3048)
			(end -0.67945 0.3048)
			(stroke
				(width 0.1)
				(type default)
			)
			(layer "F.Fab")
		)
		(fp_line
			(start -0.12065 0.2794)
			(end -0.12065 0.3048)
			(stroke
				(width 0.1)
				(type default)
			)
			(layer "F.Fab")
		)
		(fp_line
			(start -0.12065 -0.2794)
			(end 0.12065 -0.2794)
			(stroke
				(width 0.1)
				(type default)
			)
			(layer "F.Fab")
		)
		(fp_line
			(start -0.12065 -0.305054)
			(end -0.12065 -0.2794)
			(stroke
				(width 0.1)
				(type default)
			)
			(layer "F.Fab")
		)
		(fp_line
			(start -0.67945 0.3048)
			(end -0.67945 -0.305054)
			(stroke
				(width 0.1)
				(type default)
			)
			(layer "F.Fab")
		)
		(fp_line
			(start -0.67945 -0.305054)
			(end -0.12065 -0.305054)
			(stroke
				(width 0.1)
				(type default)
			)
			(layer "F.Fab")
		)
		(pad "1" smd circle
			(at -0.40005 0 180)
			(size 0 0)
			(layers "F.Cu" "F.Mask" "F.Paste")
			(net "P12V_AUX")
		)
		(pad "2" smd circle
			(at 0.40005 0 180)
			(size 0 0)
			(layers "F.Cu" "F.Mask" "F.Paste")
			(net "GND")
		)
	)
)
